FILE_TYPE = MACRO_DRAWING;
SET COLOR_WIRE YELLOW;
SET COLOR_PROP MONO;
SET COLOR_DOT WHITE;
SET COLOR_ARC YELLOW;
SET COLOR_BODY GREEN;
SET COLOR_NOTE MONO;
SET PROP_DISPLAY VALUE;
SET PAGE_NUMBER P172;
FORCEADD OFFPAGE..2
(1500 0);
FORCEPROP 2 LAST $XR0 116 
J 0
(1689 0);
DISPLAY 0.638298 (1689 0);
PAINT MONO (1689 0);
FORCEPROP 1 LAST COMMENT_BODY TRUE
J 0
(1455 -95);
DISPLAY 1.170213 (1455 -95);
PAINT GREEN (1455 -95);
DISPLAY INVISIBLE (1455 -95);
FORCEPROP 1 LAST OFFPAGE TRUE
J 0
(1825 -125);
PAINT GREEN (1825 -125);
DISPLAY INVISIBLE (1825 -125);
FORCEPROP 2 LAST CDS_LIB mstr_standard
J 0
(1500 0);
DISPLAY 1.382979 (1500 0);
PAINT ORANGE (1500 0);
DISPLAY INVISIBLE (1500 0);
FORCEPROP 2 LAST PATH I10
J 0
(1700 50);
DISPLAY 1.021277 (1700 50);
PAINT ORANGE (1700 50);
DISPLAY INVISIBLE (1700 50);
FORCEPROP 2 LAST ROOM ST_SATA
J 0
(1700 50);
DISPLAY 1.404255 (1700 50);
PAINT ORANGE (1700 50);
DISPLAY INVISIBLE (1700 50);
FORCEADD OFFPAGE..4
(1475 150);
FORCEPROP 2 LAST $XR0 116 
J 0
(1661 150);
DISPLAY 0.638298 (1661 150);
PAINT MONO (1661 150);
FORCEPROP 1 LAST COMMENT_BODY TRUE
J 0
(1450 50);
DISPLAY 1.170213 (1450 50);
PAINT GREEN (1450 50);
DISPLAY INVISIBLE (1450 50);
FORCEPROP 2 LAST CDS_LIB mstr_standard
J 0
(1475 150);
DISPLAY 1.382979 (1475 150);
PAINT ORANGE (1475 150);
DISPLAY INVISIBLE (1475 150);
FORCEPROP 2 LAST PATH I11
J 0
(1675 200);
DISPLAY 1.021277 (1675 200);
PAINT ORANGE (1675 200);
DISPLAY INVISIBLE (1675 200);
FORCEPROP 2 LAST ROOM ST_SATA
J 0
(1675 200);
DISPLAY 1.404255 (1675 200);
PAINT ORANGE (1675 200);
DISPLAY INVISIBLE (1675 200);
FORCEPROP 1 LAST OFFPAGE TRUE
J 0
(1800 25);
PAINT GREEN (1800 25);
DISPLAY INVISIBLE (1800 25);
FORCEADD OFFPAGE..4
(1475 100);
FORCEPROP 2 LAST $XR0 116 
J 0
(1661 100);
DISPLAY 0.638298 (1661 100);
PAINT MONO (1661 100);
FORCEPROP 1 LAST COMMENT_BODY TRUE
J 0
(1450 0);
DISPLAY 1.170213 (1450 0);
PAINT GREEN (1450 0);
DISPLAY INVISIBLE (1450 0);
FORCEPROP 1 LAST OFFPAGE TRUE
J 0
(1800 -25);
PAINT GREEN (1800 -25);
DISPLAY INVISIBLE (1800 -25);
FORCEPROP 2 LAST CDS_LIB mstr_standard
J 0
(1475 100);
DISPLAY 1.382979 (1475 100);
PAINT ORANGE (1475 100);
DISPLAY INVISIBLE (1475 100);
FORCEPROP 2 LAST PATH I12
J 0
(1675 150);
DISPLAY 1.021277 (1675 150);
PAINT ORANGE (1675 150);
DISPLAY INVISIBLE (1675 150);
FORCEPROP 2 LAST ROOM ST_SATA
J 0
(1675 150);
DISPLAY 1.404255 (1675 150);
PAINT ORANGE (1675 150);
DISPLAY INVISIBLE (1675 150);
FORCEADD CONN7_E82125014..2
(-2000 50);
FORCEPROP 1 LAST PART_NUMBER E82125-014
J 0
(-2250 -350);
DISPLAY 0.617021 (-2250 -350);
PAINT BLUE (-2250 -350);
FORCEPROP 2 LASTPIN (-1700 -50) $PN 5
J 0
(-1690 -40);
DISPLAY 0.617021 (-1690 -40);
PAINT MONO (-1690 -40);
FORCEPROP 2 LASTPIN (-1700 -200) $PN MH2
J 0
(-1690 -190);
DISPLAY 0.617021 (-1690 -190);
PAINT MONO (-1690 -190);
FORCEPROP 2 LASTPIN (-1700 -100) $PN 7
J 0
(-1690 -90);
DISPLAY 0.617021 (-1690 -90);
PAINT MONO (-1690 -90);
FORCEPROP 1 LAST MATERIAL EMPTY
J 0
(-2250 500);
DISPLAY 0.617021 (-2250 500);
PAINT SKYBLUE (-2250 500);
FORCEPROP 1 LAST LOCATION J8A3
J 0
(-2250 550);
DISPLAY 0.617021 (-2250 550);
PAINT AQUA (-2250 550);
FORCEPROP 2 LASTPIN (-1700 200) $PN 1
J 0
(-1690 210);
DISPLAY 0.617021 (-1690 210);
PAINT MONO (-1690 210);
FORCEPROP 2 LASTPIN (-1700 50) $PN 4
J 0
(-1690 60);
DISPLAY 0.617021 (-1690 60);
PAINT MONO (-1690 60);
FORCEPROP 2 LASTPIN (-1700 0) $PN 6
J 0
(-1690 10);
DISPLAY 0.617021 (-1690 10);
PAINT MONO (-1690 10);
FORCEPROP 2 LASTPIN (-1700 150) $PN 2
J 0
(-1690 160);
DISPLAY 0.617021 (-1690 160);
PAINT MONO (-1690 160);
FORCEPROP 2 LASTPIN (-1700 100) $PN 3
J 0
(-1690 110);
DISPLAY 0.617021 (-1690 110);
PAINT MONO (-1690 110);
FORCEPROP 2 LASTPIN (-1700 300) $PN MH1
J 0
(-1690 310);
DISPLAY 0.617021 (-1690 310);
PAINT MONO (-1690 310);
FORCEPROP 2 LAST CDS_LOCATION J8A3
J 0
(-2250 550);
DISPLAY 0.617021 (-2250 550);
PAINT AQUA (-2250 550);
DISPLAY INVISIBLE (-2250 550);
FORCEPROP 2 LAST $SEC 1
J 0
(-2250 600);
PAINT MONO (-2250 600);
DISPLAY INVISIBLE (-2250 600);
FORCEPROP 2 LAST CDS_SEC 1
J 0
(-2250 600);
PAINT MONO (-2250 600);
DISPLAY INVISIBLE (-2250 600);
FORCEPROP 1 LAST PACK_TYPE PIP_TH
J 0
(-2250 600);
PAINT SKYBLUE (-2250 600);
DISPLAY INVISIBLE (-2250 600);
FORCEPROP 0 LAST ROOM ST_SATA
J 0
(-2250 650);
DISPLAY 1.021277 (-2250 650);
PAINT ORANGE (-2250 650);
DISPLAY INVISIBLE (-2250 650);
FORCEPROP 2 LAST CDS_LIB mstr_conn
J 0
(-2000 50);
PAINT MONO (-2000 50);
DISPLAY INVISIBLE (-2000 50);
FORCEPROP 1 LAST PATH I17
J 0
(-1950 500);
PAINT GREEN (-1950 500);
DISPLAY INVISIBLE (-1950 500);
FORCEADD GND..1
(-1650 -425);
FORCEPROP 3 LASTPIN (-1650 -375) SIG_NAME GND\g
J 0
(-1640 -365);
DISPLAY 0.659574 (-1640 -365);
PAINT MONO (-1640 -365);
DISPLAY INVISIBLE (-1640 -365);
FORCEPROP 2 LAST ROOM ST_SATA
J 0
(-1825 -350);
DISPLAY 0.617021 (-1825 -350);
PAINT ORANGE (-1825 -350);
DISPLAY INVISIBLE (-1825 -350);
FORCEPROP 1 LAST PATH I2
J 0
(-1575 -425);
DISPLAY 0.872340 (-1575 -425);
PAINT AQUA (-1575 -425);
DISPLAY INVISIBLE (-1575 -425);
FORCEPROP 1 LAST BODY_TYPE PLUMBING
J 0
(-1695 -468);
DISPLAY 0.340426 (-1695 -468);
PAINT GREEN (-1695 -468);
DISPLAY INVISIBLE (-1695 -468);
FORCEPROP 2 LAST CDS_LIB mstr_symbols
J 0
(-1650 -425);
DISPLAY 1.382979 (-1650 -425);
PAINT ORANGE (-1650 -425);
DISPLAY INVISIBLE (-1650 -425);
FORCEPROP 1 LAST SIZE 1B
J 0
(-1575 -475);
DISPLAY 0.617021 (-1575 -475);
PAINT ORANGE (-1575 -475);
DISPLAY INVISIBLE (-1575 -475);
FORCEPROP 1 LAST VOLTAGE 0
J 0
(-1650 -425);
PAINT SKYBLUE (-1650 -425);
DISPLAY INVISIBLE (-1650 -425);
FORCEPROP 1 LAST HDL_POWER GND
J 0
(-1650 -275);
DISPLAY 0.617021 (-1650 -275);
PAINT GREEN (-1650 -275);
DISPLAY INVISIBLE (-1650 -275);
FORCEADD CONN4_H73295001..1
(0 1900);
FORCEPROP 2 LASTPIN (-200 1950) $PN 1
J 2
(-210 1960);
DISPLAY 0.617021 (-210 1960);
PAINT ORANGE (-210 1960);
FORCEPROP 2 LASTPIN (-200 1900) $PN 2
J 2
(-210 1910);
DISPLAY 0.617021 (-210 1910);
PAINT ORANGE (-210 1910);
FORCEPROP 2 LASTPIN (-200 1850) $PN 3
J 2
(-210 1860);
DISPLAY 0.617021 (-210 1860);
PAINT ORANGE (-210 1860);
FORCEPROP 2 LASTPIN (-200 1800) $PN 4
J 2
(-210 1810);
DISPLAY 0.617021 (-210 1810);
PAINT ORANGE (-210 1810);
FORCEPROP 1 LAST MATERIAL EMPTY
J 0
(-150 2150);
DISPLAY 0.617021 (-150 2150);
PAINT SKYBLUE (-150 2150);
FORCEPROP 1 LAST LOCATION J8A4
J 0
(-150 2200);
DISPLAY 0.617021 (-150 2200);
PAINT AQUA (-150 2200);
FORCEPROP 1 LAST PART_NUMBER H73295-001
J 0
(-150 1700);
DISPLAY 0.617021 (-150 1700);
PAINT BLUE (-150 1700);
FORCEPROP 0 LAST ROOM ST_SATA
J 0
(-150 2300);
DISPLAY 1.021277 (-150 2300);
PAINT ORANGE (-150 2300);
DISPLAY INVISIBLE (-150 2300);
FORCEPROP 2 LAST CDS_LOCATION J8A4
J 0
(-150 2200);
DISPLAY 0.617021 (-150 2200);
PAINT AQUA (-150 2200);
DISPLAY INVISIBLE (-150 2200);
FORCEPROP 2 LAST SEC 1
J 0
(-150 2250);
DISPLAY 0.680851 (-150 2250);
PAINT MONO (-150 2250);
DISPLAY INVISIBLE (-150 2250);
FORCEPROP 2 LAST SEC_TYPE PIP
J 0
(-150 2250);
DISPLAY 1.021277 (-150 2250);
PAINT ORANGE (-150 2250);
DISPLAY INVISIBLE (-150 2250);
FORCEPROP 1 LAST PACK_TYPE PIP
J 0
(-150 2250);
PAINT SKYBLUE (-150 2250);
DISPLAY INVISIBLE (-150 2250);
FORCEPROP 2 LAST CDS_LIB mstr_conn
J 0
(0 1900);
PAINT ORANGE (0 1900);
DISPLAY INVISIBLE (0 1900);
FORCEPROP 1 LAST PATH I25
J 0
(50 2150);
PAINT GREEN (50 2150);
DISPLAY INVISIBLE (50 2150);
FORCEADD GND..1
(-300 1550);
FORCEPROP 3 LASTPIN (-300 1600) SIG_NAME GND\g
J 0
(-290 1610);
DISPLAY 0.659574 (-290 1610);
PAINT MONO (-290 1610);
DISPLAY INVISIBLE (-290 1610);
FORCEPROP 1 LAST BODY_TYPE PLUMBING
J 0
(-345 1507);
DISPLAY 0.340426 (-345 1507);
PAINT GREEN (-345 1507);
DISPLAY INVISIBLE (-345 1507);
FORCEPROP 1 LAST SIZE 1B
J 0
(-225 1500);
DISPLAY 0.617021 (-225 1500);
PAINT ORANGE (-225 1500);
DISPLAY INVISIBLE (-225 1500);
FORCEPROP 1 LAST VOLTAGE 0
J 0
(-300 1550);
PAINT SKYBLUE (-300 1550);
DISPLAY INVISIBLE (-300 1550);
FORCEPROP 2 LAST CDS_LIB mstr_symbols
J 0
(-300 1550);
PAINT ORANGE (-300 1550);
DISPLAY INVISIBLE (-300 1550);
FORCEPROP 2 LAST ROOM ST_SATA
J 0
(-475 1625);
DISPLAY 0.617021 (-475 1625);
PAINT ORANGE (-475 1625);
DISPLAY INVISIBLE (-475 1625);
FORCEPROP 1 LAST HDL_POWER GND
J 0
(-300 1700);
DISPLAY 0.617021 (-300 1700);
PAINT GREEN (-300 1700);
DISPLAY INVISIBLE (-300 1700);
FORCEPROP 1 LAST PATH I26
J 0
(-225 1550);
DISPLAY 0.872340 (-225 1550);
PAINT AQUA (-225 1550);
DISPLAY INVISIBLE (-225 1550);
FORCEADD GND..1
(-1125 1300);
FORCEPROP 3 LASTPIN (-1125 1350) SIG_NAME GND\g
J 0
(-1115 1360);
DISPLAY 0.659574 (-1115 1360);
PAINT MONO (-1115 1360);
DISPLAY INVISIBLE (-1115 1360);
FORCEPROP 2 LAST ROOM ST_SATA
J 0
(-1300 1375);
DISPLAY 0.617021 (-1300 1375);
PAINT ORANGE (-1300 1375);
DISPLAY INVISIBLE (-1300 1375);
FORCEPROP 1 LAST BODY_TYPE PLUMBING
J 0
(-1170 1257);
DISPLAY 0.340426 (-1170 1257);
PAINT GREEN (-1170 1257);
DISPLAY INVISIBLE (-1170 1257);
FORCEPROP 1 LAST SIZE 1B
J 0
(-1050 1250);
DISPLAY 0.617021 (-1050 1250);
PAINT ORANGE (-1050 1250);
DISPLAY INVISIBLE (-1050 1250);
FORCEPROP 1 LAST PATH I35
J 0
(-1050 1300);
DISPLAY 0.872340 (-1050 1300);
PAINT AQUA (-1050 1300);
DISPLAY INVISIBLE (-1050 1300);
FORCEPROP 2 LAST CDS_LIB mstr_symbols
J 0
(-1125 1300);
PAINT ORANGE (-1125 1300);
DISPLAY INVISIBLE (-1125 1300);
FORCEPROP 1 LAST VOLTAGE 0
J 0
(-1125 1300);
PAINT SKYBLUE (-1125 1300);
DISPLAY INVISIBLE (-1125 1300);
FORCEPROP 1 LAST HDL_POWER GND
J 0
(-1125 1450);
DISPLAY 0.617021 (-1125 1450);
PAINT GREEN (-1125 1450);
DISPLAY INVISIBLE (-1125 1450);
FORCEADD CAP..1
(-1125 1575);
FORCEPROP 1 LASTPIN (-1125 1475) $PN 2
J 0
(-1115 1455);
DISPLAY 0.617021 (-1115 1455);
PAINT ORANGE (-1115 1455);
FORCEPROP 1 LASTPIN (-1125 1675) $PN 1
J 0
(-1115 1655);
DISPLAY 0.617021 (-1115 1655);
PAINT ORANGE (-1115 1655);
FORCEPROP 1 LAST MATERIAL X6S
J 0
(-1075 1475);
DISPLAY 0.617021 (-1075 1475);
PAINT SKYBLUE (-1075 1475);
FORCEPROP 1 LAST VOLTAGE 16V
J 0
(-1075 1575);
DISPLAY 0.617021 (-1075 1575);
PAINT SKYBLUE (-1075 1575);
FORCEPROP 1 LAST PACK_TYPE 0805
J 0
(-1075 1375);
DISPLAY 0.617021 (-1075 1375);
PAINT SKYBLUE (-1075 1375);
FORCEPROP 1 LAST TOLERANCE 10%
J 0
(-1075 1525);
DISPLAY 0.617021 (-1075 1525);
PAINT SKYBLUE (-1075 1525);
FORCEPROP 1 LAST VALUE 10UF
J 0
(-1075 1625);
DISPLAY 0.617021 (-1075 1625);
PAINT SKYBLUE (-1075 1625);
FORCEPROP 1 LAST PART_NUMBER C95333-007
J 0
(-1075 1425);
DISPLAY 0.617021 (-1075 1425);
PAINT BLUE (-1075 1425);
FORCEPROP 1 LAST LOCATION C9B2
J 0
(-1075 1675);
DISPLAY 0.617021 (-1075 1675);
PAINT AQUA (-1075 1675);
FORCEPROP 2 LAST ROOM ST_SATA
J 0
(-1075 1725);
DISPLAY 1.361702 (-1075 1725);
PAINT ORANGE (-1075 1725);
DISPLAY INVISIBLE (-1075 1725);
FORCEPROP 1 LAST PATH I36
J 0
(-1075 1725);
DISPLAY 0.978723 (-1075 1725);
PAINT WHITE (-1075 1725);
DISPLAY INVISIBLE (-1075 1725);
FORCEPROP 2 LAST CDS_LOCATION C9B2
J 0
(-1075 1675);
DISPLAY 0.617021 (-1075 1675);
PAINT AQUA (-1075 1675);
DISPLAY INVISIBLE (-1075 1675);
FORCEPROP 2 LAST CDS_LIB mstr_discrete
J 0
(-1125 1575);
PAINT ORANGE (-1125 1575);
DISPLAY INVISIBLE (-1125 1575);
FORCEPROP 2 LAST SEC 1
J 0
(-1075 1775);
PAINT MONO (-1075 1775);
DISPLAY INVISIBLE (-1075 1775);
FORCEPROP 2 LAST SEC_TYPE 0805
J 0
(-1075 1775);
DISPLAY 1.021277 (-1075 1775);
PAINT ORANGE (-1075 1775);
DISPLAY INVISIBLE (-1075 1775);
FORCEADD P12V..1
(-2100 2075);
FORCEPROP 3 LASTPIN (-2100 2025) SIG_NAME P12V\g
J 0
(-2090 2035);
DISPLAY 0.659574 (-2090 2035);
PAINT MONO (-2090 2035);
DISPLAY INVISIBLE (-2090 2035);
FORCEPROP 1 LAST HDL_POWER P12V
J 0
(-2300 1925);
DISPLAY 0.872340 (-2300 1925);
PAINT ORANGE (-2300 1925);
DISPLAY INVISIBLE (-2300 1925);
FORCEPROP 1 LAST BODY_TYPE PLUMBING
J 0
(-2145 2032);
DISPLAY 0.340426 (-2145 2032);
PAINT GREEN (-2145 2032);
DISPLAY INVISIBLE (-2145 2032);
FORCEPROP 1 LAST VOLTAGE 12.0V
J 0
(-2145 2032);
DISPLAY 0.340426 (-2145 2032);
PAINT SKYBLUE (-2145 2032);
DISPLAY INVISIBLE (-2145 2032);
FORCEPROP 1 LAST PATH I37
J 0
(-2055 2077);
DISPLAY 0.340426 (-2055 2077);
PAINT GREEN (-2055 2077);
DISPLAY INVISIBLE (-2055 2077);
FORCEPROP 2 LAST CDS_LIB mstr_symbols
J 0
(-2100 2075);
PAINT ORANGE (-2100 2075);
DISPLAY INVISIBLE (-2100 2075);
FORCEPROP 1 LAST SIZE 1B
J 0
(-2055 2097);
DISPLAY 0.340426 (-2055 2097);
PAINT GREEN (-2055 2097);
DISPLAY INVISIBLE (-2055 2097);
FORCEADD FUSE..1
(-1825 1800);
FORCEPROP 1 LASTPIN (-1975 1800) $PN 1
J 0
(-1990 1810);
DISPLAY 0.617021 (-1990 1810);
PAINT ORANGE (-1990 1810);
FORCEPROP 1 LAST MATERIAL IC
J 0
(-1975 1850);
DISPLAY 0.617021 (-1975 1850);
PAINT SKYBLUE (-1975 1850);
FORCEPROP 1 LAST PART_NUMBER C94311-016
J 0
(-1950 1725);
DISPLAY 0.617021 (-1950 1725);
PAINT BLUE (-1950 1725);
FORCEPROP 1 LASTPIN (-1675 1800) $PN 2
J 0
(-1690 1810);
DISPLAY 0.617021 (-1690 1810);
PAINT ORANGE (-1690 1810);
FORCEPROP 1 LAST LOCATION F9B1
J 0
(-1975 1900);
DISPLAY 0.617021 (-1975 1900);
PAINT AQUA (-1975 1900);
FORCEPROP 2 LAST CDS_LOCATION F9B1
J 0
(-1975 1900);
DISPLAY 0.617021 (-1975 1900);
PAINT AQUA (-1975 1900);
DISPLAY INVISIBLE (-1975 1900);
FORCEPROP 2 LAST SEC 1
J 0
(-1975 1950);
PAINT MONO (-1975 1950);
DISPLAY INVISIBLE (-1975 1950);
FORCEPROP 2 LAST SEC_TYPE SM
J 0
(-1975 1950);
DISPLAY 1.021277 (-1975 1950);
PAINT ORANGE (-1975 1950);
DISPLAY INVISIBLE (-1975 1950);
FORCEPROP 1 LAST PACK_TYPE SM
J 0
(-1975 1950);
DISPLAY 0.978723 (-1975 1950);
PAINT SKYBLUE (-1975 1950);
DISPLAY INVISIBLE (-1975 1950);
FORCEPROP 0 LAST ROOM ST_SATA
J 0
(-1975 2000);
DISPLAY 1.021277 (-1975 2000);
PAINT ORANGE (-1975 2000);
DISPLAY INVISIBLE (-1975 2000);
FORCEPROP 2 LAST CDS_LIB mstr_discrete
J 0
(-1825 1800);
PAINT ORANGE (-1825 1800);
DISPLAY INVISIBLE (-1825 1800);
FORCEPROP 1 LAST PATH I38
J 0
(-1525 1850);
DISPLAY 0.978723 (-1525 1850);
PAINT BLUE (-1525 1850);
DISPLAY INVISIBLE (-1525 1850);
FORCEADD CAP..1
(-700 1575);
FORCEPROP 1 LASTPIN (-700 1475) $PN 2
J 0
(-690 1455);
DISPLAY 0.617021 (-690 1455);
PAINT ORANGE (-690 1455);
FORCEPROP 1 LAST PACK_TYPE 0805
J 0
(-650 1375);
DISPLAY 0.617021 (-650 1375);
PAINT SKYBLUE (-650 1375);
FORCEPROP 1 LAST MATERIAL X6S
J 0
(-650 1475);
DISPLAY 0.617021 (-650 1475);
PAINT SKYBLUE (-650 1475);
FORCEPROP 1 LAST TOLERANCE 10%
J 0
(-650 1525);
DISPLAY 0.617021 (-650 1525);
PAINT SKYBLUE (-650 1525);
FORCEPROP 1 LAST VALUE 10UF
J 0
(-650 1625);
DISPLAY 0.617021 (-650 1625);
PAINT SKYBLUE (-650 1625);
FORCEPROP 1 LASTPIN (-700 1675) $PN 1
J 0
(-690 1655);
DISPLAY 0.617021 (-690 1655);
PAINT ORANGE (-690 1655);
FORCEPROP 1 LAST VOLTAGE 16V
J 0
(-650 1575);
DISPLAY 0.617021 (-650 1575);
PAINT SKYBLUE (-650 1575);
FORCEPROP 1 LAST PART_NUMBER C95333-007
J 0
(-650 1425);
DISPLAY 0.617021 (-650 1425);
PAINT BLUE (-650 1425);
FORCEPROP 1 LAST LOCATION C9B1
J 0
(-650 1675);
DISPLAY 0.617021 (-650 1675);
PAINT AQUA (-650 1675);
FORCEPROP 2 LAST CDS_LOCATION C9B1
J 0
(-650 1675);
DISPLAY 0.617021 (-650 1675);
PAINT AQUA (-650 1675);
DISPLAY INVISIBLE (-650 1675);
FORCEPROP 2 LAST CDS_LIB mstr_discrete
J 0
(-700 1575);
PAINT ORANGE (-700 1575);
DISPLAY INVISIBLE (-700 1575);
FORCEPROP 1 LAST PATH I39
J 0
(-650 1725);
DISPLAY 0.978723 (-650 1725);
PAINT WHITE (-650 1725);
DISPLAY INVISIBLE (-650 1725);
FORCEPROP 2 LAST ROOM ST_SATA
J 0
(-650 1725);
DISPLAY 1.361702 (-650 1725);
PAINT ORANGE (-650 1725);
DISPLAY INVISIBLE (-650 1725);
FORCEPROP 2 LAST SEC_TYPE 0805
J 0
(-650 1775);
DISPLAY 1.021277 (-650 1775);
PAINT ORANGE (-650 1775);
DISPLAY INVISIBLE (-650 1775);
FORCEPROP 2 LAST SEC 1
J 0
(-650 1775);
PAINT MONO (-650 1775);
DISPLAY INVISIBLE (-650 1775);
FORCEADD GND..1
(-700 1300);
FORCEPROP 3 LASTPIN (-700 1350) SIG_NAME GND\g
J 0
(-690 1360);
DISPLAY 0.659574 (-690 1360);
PAINT MONO (-690 1360);
DISPLAY INVISIBLE (-690 1360);
FORCEPROP 2 LAST ROOM ST_SATA
J 0
(-875 1375);
DISPLAY 0.617021 (-875 1375);
PAINT ORANGE (-875 1375);
DISPLAY INVISIBLE (-875 1375);
FORCEPROP 1 LAST BODY_TYPE PLUMBING
J 0
(-745 1257);
DISPLAY 0.340426 (-745 1257);
PAINT GREEN (-745 1257);
DISPLAY INVISIBLE (-745 1257);
FORCEPROP 1 LAST SIZE 1B
J 0
(-625 1250);
DISPLAY 0.617021 (-625 1250);
PAINT ORANGE (-625 1250);
DISPLAY INVISIBLE (-625 1250);
FORCEPROP 1 LAST VOLTAGE 0
J 0
(-700 1300);
PAINT SKYBLUE (-700 1300);
DISPLAY INVISIBLE (-700 1300);
FORCEPROP 2 LAST CDS_LIB mstr_symbols
J 0
(-700 1300);
PAINT ORANGE (-700 1300);
DISPLAY INVISIBLE (-700 1300);
FORCEPROP 1 LAST HDL_POWER GND
J 0
(-700 1450);
DISPLAY 0.617021 (-700 1450);
PAINT GREEN (-700 1450);
DISPLAY INVISIBLE (-700 1450);
FORCEPROP 1 LAST PATH I40
J 0
(-625 1300);
DISPLAY 0.872340 (-625 1300);
PAINT AQUA (-625 1300);
DISPLAY INVISIBLE (-625 1300);
FORCEADD FUSE..1
(-1175 1950);
FORCEPROP 1 LASTPIN (-1325 1950) $PN 1
J 0
(-1340 1960);
DISPLAY 0.617021 (-1340 1960);
PAINT ORANGE (-1340 1960);
FORCEPROP 1 LAST MATERIAL IC
J 0
(-1325 2000);
DISPLAY 0.617021 (-1325 2000);
PAINT SKYBLUE (-1325 2000);
FORCEPROP 1 LASTPIN (-1025 1950) $PN 2
J 0
(-1040 1960);
DISPLAY 0.617021 (-1040 1960);
PAINT ORANGE (-1040 1960);
FORCEPROP 1 LAST PART_NUMBER C94311-006
J 0
(-1300 1875);
DISPLAY 0.617021 (-1300 1875);
PAINT BLUE (-1300 1875);
FORCEPROP 1 LAST LOCATION F8B1
J 0
(-1325 2050);
DISPLAY 0.617021 (-1325 2050);
PAINT AQUA (-1325 2050);
FORCEPROP 2 LAST CDS_LIB mstr_discrete
J 0
(-1175 1950);
PAINT ORANGE (-1175 1950);
DISPLAY INVISIBLE (-1175 1950);
FORCEPROP 1 LAST PATH I41
J 0
(-875 2000);
DISPLAY 0.978723 (-875 2000);
PAINT BLUE (-875 2000);
DISPLAY INVISIBLE (-875 2000);
FORCEPROP 1 LAST PACK_TYPE SMLF
J 0
(-1325 2100);
DISPLAY 0.978723 (-1325 2100);
PAINT SKYBLUE (-1325 2100);
DISPLAY INVISIBLE (-1325 2100);
FORCEPROP 2 LAST SEC_TYPE SMLF
J 0
(-1325 2100);
DISPLAY 1.021277 (-1325 2100);
PAINT ORANGE (-1325 2100);
DISPLAY INVISIBLE (-1325 2100);
FORCEPROP 2 LAST SEC 1
J 0
(-1325 2100);
PAINT MONO (-1325 2100);
DISPLAY INVISIBLE (-1325 2100);
FORCEPROP 0 LAST ROOM ST_SATA
J 0
(-1325 2150);
DISPLAY 1.021277 (-1325 2150);
PAINT ORANGE (-1325 2150);
DISPLAY INVISIBLE (-1325 2150);
FORCEPROP 2 LAST CDS_LOCATION F8B1
J 0
(-1325 2050);
DISPLAY 0.617021 (-1325 2050);
PAINT AQUA (-1325 2050);
DISPLAY INVISIBLE (-1325 2050);
FORCEADD P5V..1
(-1425 2275);
FORCEPROP 3 LASTPIN (-1425 2225) SIG_NAME P5V\g
J 0
(-1415 2235);
DISPLAY 0.659574 (-1415 2235);
PAINT MONO (-1415 2235);
DISPLAY INVISIBLE (-1415 2235);
FORCEPROP 1 LAST HDL_POWER P5V
J 0
(-1725 2150);
DISPLAY 0.872340 (-1725 2150);
PAINT ORANGE (-1725 2150);
DISPLAY INVISIBLE (-1725 2150);
FORCEPROP 1 LAST PATH I42
J 0
(-1380 2277);
DISPLAY 0.340426 (-1380 2277);
PAINT GREEN (-1380 2277);
DISPLAY INVISIBLE (-1380 2277);
FORCEPROP 1 LAST BODY_TYPE PLUMBING
J 0
(-1470 2232);
DISPLAY 0.340426 (-1470 2232);
PAINT GREEN (-1470 2232);
DISPLAY INVISIBLE (-1470 2232);
FORCEPROP 2 LAST CDS_LIB mstr_symbols
J 0
(-1425 2275);
PAINT ORANGE (-1425 2275);
DISPLAY INVISIBLE (-1425 2275);
FORCEPROP 1 LAST SIZE 1B
J 0
(-1380 2297);
DISPLAY 0.340426 (-1380 2297);
PAINT GREEN (-1380 2297);
DISPLAY INVISIBLE (-1380 2297);
FORCEPROP 1 LAST VOLTAGE +5.0V
J 0
(-1350 2425);
DISPLAY 1.021277 (-1350 2425);
PAINT SKYBLUE (-1350 2425);
DISPLAY INVISIBLE (-1350 2425);
FORCEADD CAP_A..2
(575 0);
FORCEPROP 1 LAST MATERIAL X7R
J 0
(575 -150);
DISPLAY 0.617021 (575 -150);
PAINT SKYBLUE (575 -150);
FORCEPROP 1 LAST VOLTAGE 25V
J 0
(575 -100);
DISPLAY 0.617021 (575 -100);
PAINT SKYBLUE (575 -100);
FORCEPROP 1 LAST PACK_TYPE 0402V
J 1
(575 -200);
DISPLAY 0.617021 (575 -200);
PAINT SKYBLUE (575 -200);
FORCEPROP 1 LAST TOLERANCE 10%
J 2
(575 -150);
DISPLAY 0.617021 (575 -150);
PAINT SKYBLUE (575 -150);
FORCEPROP 1 LAST VALUE 0.01UF
J 2
(575 -100);
DISPLAY 0.617021 (575 -100);
PAINT SKYBLUE (575 -100);
FORCEPROP 1 LASTPIN (475 0) $PN 1
J 0
(465 15);
DISPLAY 0.617021 (465 15);
PAINT MONO (465 15);
FORCEPROP 1 LAST PART_NUMBER A36096-045
J 1
(575 50);
DISPLAY 0.617021 (575 50);
PAINT BLUE (575 50);
FORCEPROP 1 LAST LOCATION C2L49
J 1
(575 100);
DISPLAY 0.617021 (575 100);
PAINT AQUA (575 100);
FORCEPROP 1 LASTPIN (675 0) $PN 2
J 0
(660 15);
DISPLAY 0.617021 (660 15);
PAINT MONO (660 15);
FORCEPROP 2 LAST CDS_LIB dev_discrete
J 0
(575 0);
PAINT ORANGE (575 0);
DISPLAY INVISIBLE (575 0);
FORCEPROP 2 LAST ROOM ST_SATA
J 1
(575 140);
DISPLAY 0.787234 (575 140);
PAINT SKYBLUE (575 140);
DISPLAY INVISIBLE (575 140);
FORCEPROP 1 LAST PATH I5
J 0
(575 200);
DISPLAY 0.978723 (575 200);
PAINT WHITE (575 200);
DISPLAY INVISIBLE (575 200);
FORCEPROP 2 LAST SEC 1
J 0
(575 250);
DISPLAY 0.936170 (575 250);
PAINT MONO (575 250);
DISPLAY INVISIBLE (575 250);
FORCEPROP 2 LAST SEC_TYPE 0402V
J 0
(575 250);
DISPLAY 1.404255 (575 250);
PAINT ORANGE (575 250);
DISPLAY INVISIBLE (575 250);
FORCEPROP 2 LAST CDS_SEC 1
J 0
(575 150);
PAINT ORANGE (575 150);
DISPLAY INVISIBLE (575 150);
FORCEPROP 2 LAST CDS_LOCATION C2L49
J 1
(575 100);
DISPLAY 0.617021 (575 100);
PAINT AQUA (575 100);
DISPLAY INVISIBLE (575 100);
FORCEADD GND..1
(-1675 -1550);
FORCEPROP 3 LASTPIN (-1675 -1500) SIG_NAME GND\g
J 0
(-1665 -1490);
DISPLAY 0.659574 (-1665 -1490);
PAINT MONO (-1665 -1490);
DISPLAY INVISIBLE (-1665 -1490);
FORCEPROP 1 LAST BODY_TYPE PLUMBING
J 0
(-1720 -1593);
DISPLAY 0.340426 (-1720 -1593);
PAINT GREEN (-1720 -1593);
DISPLAY INVISIBLE (-1720 -1593);
FORCEPROP 1 LAST SIZE 1B
J 0
(-1600 -1600);
DISPLAY 0.617021 (-1600 -1600);
PAINT ORANGE (-1600 -1600);
DISPLAY INVISIBLE (-1600 -1600);
FORCEPROP 1 LAST PATH I51
J 0
(-1600 -1550);
DISPLAY 0.872340 (-1600 -1550);
PAINT AQUA (-1600 -1550);
DISPLAY INVISIBLE (-1600 -1550);
FORCEPROP 2 LAST CDS_LIB mstr_symbols
J 0
(-1675 -1550);
DISPLAY 1.382979 (-1675 -1550);
PAINT ORANGE (-1675 -1550);
DISPLAY INVISIBLE (-1675 -1550);
FORCEPROP 1 LAST VOLTAGE 0
J 0
(-1675 -1550);
PAINT SKYBLUE (-1675 -1550);
DISPLAY INVISIBLE (-1675 -1550);
FORCEPROP 2 LAST ROOM ST_SATA
J 0
(-1850 -1475);
DISPLAY 0.617021 (-1850 -1475);
PAINT ORANGE (-1850 -1475);
DISPLAY INVISIBLE (-1850 -1475);
FORCEPROP 1 LAST HDL_POWER GND
J 0
(-1675 -1400);
DISPLAY 0.617021 (-1675 -1400);
PAINT GREEN (-1675 -1400);
DISPLAY INVISIBLE (-1675 -1400);
FORCEADD CONN7_E82125014..2
(-2025 -1075);
FORCEPROP 1 LAST MATERIAL CONN
J 0
(-2275 -625);
DISPLAY 0.617021 (-2275 -625);
PAINT RED (-2275 -625);
FORCEPROP 1 LAST LOCATION J2M1
J 0
(-2275 -575);
DISPLAY 0.617021 (-2275 -575);
PAINT AQUA (-2275 -575);
FORCEPROP 1 LAST PART_NUMBER E82125-014
J 0
(-2275 -1475);
DISPLAY 0.617021 (-2275 -1475);
PAINT BLUE (-2275 -1475);
FORCEPROP 2 LASTPIN (-1725 -1325) $PN MH2
J 0
(-1715 -1315);
DISPLAY 0.617021 (-1715 -1315);
PAINT MONO (-1715 -1315);
FORCEPROP 2 LASTPIN (-1725 -1225) $PN 7
J 0
(-1715 -1215);
DISPLAY 0.617021 (-1715 -1215);
PAINT MONO (-1715 -1215);
FORCEPROP 2 LASTPIN (-1725 -1175) $PN 5
J 0
(-1715 -1165);
DISPLAY 0.617021 (-1715 -1165);
PAINT MONO (-1715 -1165);
FORCEPROP 2 LASTPIN (-1725 -1125) $PN 6
J 0
(-1715 -1115);
DISPLAY 0.617021 (-1715 -1115);
PAINT MONO (-1715 -1115);
FORCEPROP 2 LASTPIN (-1725 -1075) $PN 4
J 0
(-1715 -1065);
DISPLAY 0.617021 (-1715 -1065);
PAINT MONO (-1715 -1065);
FORCEPROP 2 LASTPIN (-1725 -1025) $PN 3
J 0
(-1715 -1015);
DISPLAY 0.617021 (-1715 -1015);
PAINT MONO (-1715 -1015);
FORCEPROP 2 LASTPIN (-1725 -975) $PN 2
J 0
(-1715 -965);
DISPLAY 0.617021 (-1715 -965);
PAINT MONO (-1715 -965);
FORCEPROP 2 LASTPIN (-1725 -925) $PN 1
J 0
(-1715 -915);
DISPLAY 0.617021 (-1715 -915);
PAINT MONO (-1715 -915);
FORCEPROP 2 LASTPIN (-1725 -825) $PN MH1
J 0
(-1715 -815);
DISPLAY 0.617021 (-1715 -815);
PAINT MONO (-1715 -815);
FORCEPROP 0 LAST ROOM ST_SATA
J 0
(-2275 -475);
DISPLAY 1.021277 (-2275 -475);
PAINT ORANGE (-2275 -475);
DISPLAY INVISIBLE (-2275 -475);
FORCEPROP 2 LAST CDS_LOCATION J2M1
J 0
(-2275 -575);
DISPLAY 0.617021 (-2275 -575);
PAINT AQUA (-2275 -575);
DISPLAY INVISIBLE (-2275 -575);
FORCEPROP 2 LAST $SEC 1
J 0
(-2275 -525);
PAINT MONO (-2275 -525);
DISPLAY INVISIBLE (-2275 -525);
FORCEPROP 2 LAST CDS_SEC 1
J 0
(-2275 -525);
PAINT MONO (-2275 -525);
DISPLAY INVISIBLE (-2275 -525);
FORCEPROP 1 LAST PACK_TYPE PIP_TH
J 0
(-2275 -525);
PAINT SKYBLUE (-2275 -525);
DISPLAY INVISIBLE (-2275 -525);
FORCEPROP 2 LAST CDS_LIB mstr_conn
J 0
(-2025 -1075);
PAINT MONO (-2025 -1075);
DISPLAY INVISIBLE (-2025 -1075);
FORCEPROP 1 LAST PATH I52
J 0
(-1975 -625);
PAINT GREEN (-1975 -625);
DISPLAY INVISIBLE (-1975 -625);
FORCEADD CONN4_H73295001..1
(25 925);
FORCEPROP 2 LASTPIN (-175 825) $PN 4
J 2
(-185 835);
DISPLAY 0.617021 (-185 835);
PAINT ORANGE (-185 835);
FORCEPROP 2 LASTPIN (-175 875) $PN 3
J 2
(-185 885);
DISPLAY 0.617021 (-185 885);
PAINT ORANGE (-185 885);
FORCEPROP 2 LASTPIN (-175 925) $PN 2
J 2
(-185 935);
DISPLAY 0.617021 (-185 935);
PAINT ORANGE (-185 935);
FORCEPROP 2 LASTPIN (-175 975) $PN 1
J 2
(-185 985);
DISPLAY 0.617021 (-185 985);
PAINT ORANGE (-185 985);
FORCEPROP 1 LAST MATERIAL CONN
J 0
(-125 1175);
DISPLAY 0.617021 (-125 1175);
PAINT RED (-125 1175);
FORCEPROP 1 LAST LOCATION J2L1
J 0
(-125 1225);
DISPLAY 0.617021 (-125 1225);
PAINT AQUA (-125 1225);
FORCEPROP 1 LAST PART_NUMBER H73295-001
J 0
(-125 725);
DISPLAY 0.617021 (-125 725);
PAINT BLUE (-125 725);
FORCEPROP 0 LAST ROOM ST_SATA
J 0
(-125 1325);
DISPLAY 1.021277 (-125 1325);
PAINT ORANGE (-125 1325);
DISPLAY INVISIBLE (-125 1325);
FORCEPROP 2 LAST CDS_LOCATION J2L1
J 0
(-125 1225);
DISPLAY 0.617021 (-125 1225);
PAINT AQUA (-125 1225);
DISPLAY INVISIBLE (-125 1225);
FORCEPROP 2 LAST SEC 1
J 0
(-125 1275);
DISPLAY 0.680851 (-125 1275);
PAINT MONO (-125 1275);
DISPLAY INVISIBLE (-125 1275);
FORCEPROP 2 LAST SEC_TYPE PIP
J 0
(-125 1275);
DISPLAY 1.021277 (-125 1275);
PAINT ORANGE (-125 1275);
DISPLAY INVISIBLE (-125 1275);
FORCEPROP 1 LAST PACK_TYPE PIP
J 0
(-125 1275);
PAINT SKYBLUE (-125 1275);
DISPLAY INVISIBLE (-125 1275);
FORCEPROP 2 LAST CDS_LIB mstr_conn
J 0
(25 925);
PAINT ORANGE (25 925);
DISPLAY INVISIBLE (25 925);
FORCEPROP 1 LAST PATH I53
J 0
(75 1175);
PAINT GREEN (75 1175);
DISPLAY INVISIBLE (75 1175);
FORCEADD GND..1
(-325 575);
FORCEPROP 3 LASTPIN (-325 625) SIG_NAME GND\g
J 0
(-315 635);
DISPLAY 0.659574 (-315 635);
PAINT MONO (-315 635);
DISPLAY INVISIBLE (-315 635);
FORCEPROP 1 LAST VOLTAGE 0
J 0
(-325 575);
PAINT SKYBLUE (-325 575);
DISPLAY INVISIBLE (-325 575);
FORCEPROP 2 LAST CDS_LIB mstr_symbols
J 0
(-325 575);
PAINT ORANGE (-325 575);
DISPLAY INVISIBLE (-325 575);
FORCEPROP 1 LAST BODY_TYPE PLUMBING
J 0
(-370 532);
DISPLAY 0.340426 (-370 532);
PAINT GREEN (-370 532);
DISPLAY INVISIBLE (-370 532);
FORCEPROP 2 LAST ROOM ST_SATA
J 0
(-500 650);
DISPLAY 0.617021 (-500 650);
PAINT ORANGE (-500 650);
DISPLAY INVISIBLE (-500 650);
FORCEPROP 1 LAST HDL_POWER GND
J 0
(-325 725);
DISPLAY 0.617021 (-325 725);
PAINT GREEN (-325 725);
DISPLAY INVISIBLE (-325 725);
FORCEPROP 1 LAST SIZE 1B
J 0
(-250 525);
DISPLAY 0.617021 (-250 525);
PAINT ORANGE (-250 525);
DISPLAY INVISIBLE (-250 525);
FORCEPROP 1 LAST PATH I54
J 0
(-250 575);
DISPLAY 0.872340 (-250 575);
PAINT AQUA (-250 575);
DISPLAY INVISIBLE (-250 575);
FORCEADD CAP_A..2
(-650 150);
FORCEPROP 1 LAST PACK_TYPE 0402V
J 1
(-650 -50);
DISPLAY 0.617021 (-650 -50);
PAINT SKYBLUE (-650 -50);
FORCEPROP 1 LAST MATERIAL X7R
J 0
(-650 0);
DISPLAY 0.617021 (-650 0);
PAINT SKYBLUE (-650 0);
FORCEPROP 1 LAST TOLERANCE 10%
J 2
(-650 0);
DISPLAY 0.617021 (-650 0);
PAINT SKYBLUE (-650 0);
FORCEPROP 1 LAST VALUE 0.01UF
J 2
(-650 50);
DISPLAY 0.617021 (-650 50);
PAINT SKYBLUE (-650 50);
FORCEPROP 1 LASTPIN (-550 150) $PN 2
J 0
(-565 165);
DISPLAY 0.617021 (-565 165);
PAINT MONO (-565 165);
FORCEPROP 1 LAST VOLTAGE 25V
J 0
(-650 50);
DISPLAY 0.617021 (-650 50);
PAINT SKYBLUE (-650 50);
FORCEPROP 1 LASTPIN (-750 150) $PN 1
J 0
(-760 165);
DISPLAY 0.617021 (-760 165);
PAINT MONO (-760 165);
FORCEPROP 1 LAST LOCATION C2L52
J 1
(-650 250);
DISPLAY 0.617021 (-650 250);
PAINT AQUA (-650 250);
FORCEPROP 1 LAST PART_NUMBER A36096-045
J 1
(-650 200);
DISPLAY 0.617021 (-650 200);
PAINT BLUE (-650 200);
FORCEPROP 2 LAST CDS_LIB dev_discrete
J 0
(-650 150);
PAINT ORANGE (-650 150);
DISPLAY INVISIBLE (-650 150);
FORCEPROP 2 LAST CDS_LOCATION C2L52
J 1
(-650 250);
DISPLAY 0.617021 (-650 250);
PAINT AQUA (-650 250);
DISPLAY INVISIBLE (-650 250);
FORCEPROP 2 LAST CDS_SEC 1
J 0
(-650 300);
PAINT ORANGE (-650 300);
DISPLAY INVISIBLE (-650 300);
FORCEPROP 2 LAST SEC_TYPE 0402V
J 0
(-650 400);
DISPLAY 1.404255 (-650 400);
PAINT ORANGE (-650 400);
DISPLAY INVISIBLE (-650 400);
FORCEPROP 2 LAST SEC 1
J 0
(-650 400);
DISPLAY 0.936170 (-650 400);
PAINT MONO (-650 400);
DISPLAY INVISIBLE (-650 400);
FORCEPROP 1 LAST PATH I6
J 0
(-650 350);
DISPLAY 0.978723 (-650 350);
PAINT WHITE (-650 350);
DISPLAY INVISIBLE (-650 350);
FORCEPROP 2 LAST ROOM ST_SATA
J 1
(-650 290);
DISPLAY 0.787234 (-650 290);
PAINT SKYBLUE (-650 290);
DISPLAY INVISIBLE (-650 290);
FORCEADD CAP_A..2
(-300 -50);
FORCEPROP 1 LAST VALUE 0.01UF
J 2
(-300 -150);
DISPLAY 0.617021 (-300 -150);
PAINT SKYBLUE (-300 -150);
FORCEPROP 1 LASTPIN (-400 -50) $PN 1
J 0
(-410 -35);
DISPLAY 0.617021 (-410 -35);
PAINT MONO (-410 -35);
FORCEPROP 1 LAST TOLERANCE 10%
J 2
(-300 -200);
DISPLAY 0.617021 (-300 -200);
PAINT SKYBLUE (-300 -200);
FORCEPROP 1 LAST MATERIAL X7R
J 0
(-300 -200);
DISPLAY 0.617021 (-300 -200);
PAINT SKYBLUE (-300 -200);
FORCEPROP 1 LAST VOLTAGE 25V
J 0
(-300 -150);
DISPLAY 0.617021 (-300 -150);
PAINT SKYBLUE (-300 -150);
FORCEPROP 1 LAST PACK_TYPE 0402V
J 1
(-300 -250);
DISPLAY 0.617021 (-300 -250);
PAINT SKYBLUE (-300 -250);
FORCEPROP 1 LASTPIN (-200 -50) $PN 2
J 0
(-215 -35);
DISPLAY 0.617021 (-215 -35);
PAINT MONO (-215 -35);
FORCEPROP 1 LAST PART_NUMBER A36096-045
J 1
(-300 0);
DISPLAY 0.617021 (-300 0);
PAINT BLUE (-300 0);
FORCEPROP 1 LAST LOCATION C2L50
J 1
(-300 50);
DISPLAY 0.617021 (-300 50);
PAINT AQUA (-300 50);
FORCEPROP 2 LAST CDS_LIB dev_discrete
J 0
(-300 -50);
PAINT ORANGE (-300 -50);
DISPLAY INVISIBLE (-300 -50);
FORCEPROP 2 LAST ROOM ST_SATA
J 1
(-300 90);
DISPLAY 0.787234 (-300 90);
PAINT SKYBLUE (-300 90);
DISPLAY INVISIBLE (-300 90);
FORCEPROP 1 LAST PATH I7
J 0
(-300 150);
DISPLAY 0.978723 (-300 150);
PAINT WHITE (-300 150);
DISPLAY INVISIBLE (-300 150);
FORCEPROP 2 LAST SEC 1
J 0
(-300 200);
DISPLAY 0.936170 (-300 200);
PAINT MONO (-300 200);
DISPLAY INVISIBLE (-300 200);
FORCEPROP 2 LAST SEC_TYPE 0402V
J 0
(-300 200);
DISPLAY 1.404255 (-300 200);
PAINT ORANGE (-300 200);
DISPLAY INVISIBLE (-300 200);
FORCEPROP 2 LAST CDS_SEC 1
J 0
(-300 100);
PAINT ORANGE (-300 100);
DISPLAY INVISIBLE (-300 100);
FORCEPROP 2 LAST CDS_LOCATION C2L50
J 1
(-300 50);
DISPLAY 0.617021 (-300 50);
PAINT AQUA (-300 50);
DISPLAY INVISIBLE (-300 50);
FORCEADD CAP_A..2
(100 100);
FORCEPROP 1 LASTPIN (0 100) $PN 1
J 0
(-10 115);
DISPLAY 0.617021 (-10 115);
PAINT MONO (-10 115);
FORCEPROP 1 LAST VALUE 0.01UF
J 2
(100 0);
DISPLAY 0.617021 (100 0);
PAINT SKYBLUE (100 0);
FORCEPROP 1 LAST PART_NUMBER A36096-045
J 1
(100 150);
DISPLAY 0.617021 (100 150);
PAINT BLUE (100 150);
FORCEPROP 1 LAST MATERIAL X7R
J 0
(100 -50);
DISPLAY 0.617021 (100 -50);
PAINT SKYBLUE (100 -50);
FORCEPROP 1 LAST PACK_TYPE 0402V
J 1
(100 -100);
DISPLAY 0.617021 (100 -100);
PAINT SKYBLUE (100 -100);
FORCEPROP 1 LAST TOLERANCE 10%
J 2
(100 -50);
DISPLAY 0.617021 (100 -50);
PAINT SKYBLUE (100 -50);
FORCEPROP 1 LAST VOLTAGE 25V
J 0
(100 0);
DISPLAY 0.617021 (100 0);
PAINT SKYBLUE (100 0);
FORCEPROP 1 LAST LOCATION C2L51
J 1
(100 200);
DISPLAY 0.617021 (100 200);
PAINT AQUA (100 200);
FORCEPROP 1 LASTPIN (200 100) $PN 2
J 0
(185 115);
DISPLAY 0.617021 (185 115);
PAINT MONO (185 115);
FORCEPROP 2 LAST CDS_LIB dev_discrete
J 0
(100 100);
PAINT ORANGE (100 100);
DISPLAY INVISIBLE (100 100);
FORCEPROP 2 LAST CDS_SEC 1
J 0
(100 250);
PAINT ORANGE (100 250);
DISPLAY INVISIBLE (100 250);
FORCEPROP 2 LAST SEC_TYPE 0402V
J 0
(100 350);
DISPLAY 1.404255 (100 350);
PAINT ORANGE (100 350);
DISPLAY INVISIBLE (100 350);
FORCEPROP 2 LAST SEC 1
J 0
(100 350);
DISPLAY 0.936170 (100 350);
PAINT MONO (100 350);
DISPLAY INVISIBLE (100 350);
FORCEPROP 1 LAST PATH I8
J 0
(100 300);
DISPLAY 0.978723 (100 300);
PAINT WHITE (100 300);
DISPLAY INVISIBLE (100 300);
FORCEPROP 2 LAST ROOM ST_SATA
J 1
(100 240);
DISPLAY 0.787234 (100 240);
PAINT SKYBLUE (100 240);
DISPLAY INVISIBLE (100 240);
FORCEPROP 2 LAST CDS_LOCATION C2L51
J 1
(100 200);
DISPLAY 0.617021 (100 200);
PAINT AQUA (100 200);
DISPLAY INVISIBLE (100 200);
FORCEADD OFFPAGE..2
(1500 -50);
FORCEPROP 2 LAST $XR0 116 
J 0
(1689 -50);
DISPLAY 0.638298 (1689 -50);
PAINT MONO (1689 -50);
FORCEPROP 1 LAST COMMENT_BODY TRUE
J 0
(1455 -145);
DISPLAY 1.170213 (1455 -145);
PAINT GREEN (1455 -145);
DISPLAY INVISIBLE (1455 -145);
FORCEPROP 1 LAST OFFPAGE TRUE
J 0
(1825 -175);
PAINT GREEN (1825 -175);
DISPLAY INVISIBLE (1825 -175);
FORCEPROP 2 LAST PATH I9
J 0
(1700 0);
DISPLAY 1.021277 (1700 0);
PAINT ORANGE (1700 0);
DISPLAY INVISIBLE (1700 0);
FORCEPROP 2 LAST CDS_LIB mstr_standard
J 0
(1500 -50);
DISPLAY 1.382979 (1500 -50);
PAINT ORANGE (1500 -50);
DISPLAY INVISIBLE (1500 -50);
FORCEPROP 2 LAST ROOM ST_SATA
J 0
(1700 0);
DISPLAY 1.404255 (1700 0);
PAINT ORANGE (1700 0);
DISPLAY INVISIBLE (1700 0);
FORCEADD DESIGN_NOTE..1
(600 950);
FORCEPROP 0 LAST L1 PLACE ON THE SECONDARY SIDE
J 0
(425 825);
DISPLAY 0.829787 (425 825);
PAINT WHITE (425 825);
FORCEPROP 2 LAST ROOM ST_SATA
J 0
(475 775);
DISPLAY 1.361702 (475 775);
PAINT ORANGE (475 775);
DISPLAY INVISIBLE (475 775);
FORCEPROP 2 LAST BOM_COST ST_SATA
J 0
(475 775);
DISPLAY 1.361702 (475 775);
PAINT ORANGE (475 775);
DISPLAY INVISIBLE (475 775);
FORCEPROP 2 LAST CDS_LIB mstr_symbols
J 0
(600 950);
PAINT ORANGE (600 950);
DISPLAY INVISIBLE (600 950);
FORCEPROP 1 LAST COMMENT_BODY TRUE
J 0
(625 1050);
DISPLAY 1.319149 (625 1050);
PAINT ORANGE (625 1050);
DISPLAY INVISIBLE (625 1050);
FORCEADD DNS..5
(-1995 45);
PAINT RED (-1995 45);
FORCEPROP 1 LAST COMMENT_BODY TRUE
R 1
J 0
(-1920 -180);
DISPLAY 0.872340 (-1920 -180);
PAINT GREEN (-1920 -180);
DISPLAY INVISIBLE (-1920 -180);
FORCEPROP 2 LAST CDS_LIB mstr_misc
J 0
(-1995 45);
PAINT ORANGE (-1995 45);
DISPLAY INVISIBLE (-1995 45);
FORCEADD DNS..2
(5 1895);
PAINT RED (5 1895);
FORCEPROP 1 LAST COMMENT_BODY TRUE
R 1
J 0
(80 1670);
DISPLAY 0.872340 (80 1670);
PAINT GREEN (80 1670);
DISPLAY INVISIBLE (80 1670);
FORCEPROP 2 LAST CDS_LIB mstr_misc
J 0
(5 1895);
PAINT ORANGE (5 1895);
DISPLAY INVISIBLE (5 1895);
FORCEADD DESIGN_NOTE..1
(-2850 200);
FORCEPROP 0 LAST L1 PLACE ON THE PRIMARY SIDE
J 0
(-3325 75);
DISPLAY 0.829787 (-3325 75);
PAINT WHITE (-3325 75);
FORCEPROP 0 LAST L2 POPULATE FOR SINGLE SIDED BOARD
J 0
(-3325 25);
DISPLAY 0.808511 (-3325 25);
PAINT ORANGE (-3325 25);
FORCEPROP 2 LAST ROOM ST_SATA
J 0
(-2975 25);
DISPLAY 1.361702 (-2975 25);
PAINT ORANGE (-2975 25);
DISPLAY INVISIBLE (-2975 25);
FORCEPROP 2 LAST BOM_COST ST_SATA
J 0
(-2975 25);
DISPLAY 1.361702 (-2975 25);
PAINT ORANGE (-2975 25);
DISPLAY INVISIBLE (-2975 25);
FORCEPROP 2 LAST CDS_LIB mstr_symbols
J 0
(-2850 200);
PAINT ORANGE (-2850 200);
DISPLAY INVISIBLE (-2850 200);
FORCEPROP 1 LAST COMMENT_BODY TRUE
J 0
(-2825 300);
DISPLAY 1.319149 (-2825 300);
PAINT ORANGE (-2825 300);
DISPLAY INVISIBLE (-2825 300);
FORCEADD DESIGN_NOTE..1
(-2675 -1025);
FORCEPROP 0 LAST L1 PLACE ON THE SECONDARY SIDE
J 0
(-3150 -1150);
DISPLAY 0.829787 (-3150 -1150);
PAINT WHITE (-3150 -1150);
FORCEPROP 0 LAST L2 POPULATE FOR 2-SIDED BOARD
J 0
(-3150 -1200);
DISPLAY 0.808511 (-3150 -1200);
PAINT ORANGE (-3150 -1200);
FORCEPROP 2 LAST ROOM ST_SATA
J 0
(-2800 -1200);
DISPLAY 1.361702 (-2800 -1200);
PAINT ORANGE (-2800 -1200);
DISPLAY INVISIBLE (-2800 -1200);
FORCEPROP 2 LAST BOM_COST ST_SATA
J 0
(-2800 -1200);
DISPLAY 1.361702 (-2800 -1200);
PAINT ORANGE (-2800 -1200);
DISPLAY INVISIBLE (-2800 -1200);
FORCEPROP 2 LAST CDS_LIB mstr_symbols
J 0
(-2675 -1025);
PAINT ORANGE (-2675 -1025);
DISPLAY INVISIBLE (-2675 -1025);
FORCEPROP 1 LAST COMMENT_BODY TRUE
J 0
(-2650 -925);
DISPLAY 1.319149 (-2650 -925);
PAINT ORANGE (-2650 -925);
DISPLAY INVISIBLE (-2650 -925);
FORCEADD INTEL_CORP_BPAGE..1
(3400 -2050);
FORCEPROP 1 LAST CDS_CON_LAST_MODIFIED Tue Dec 01 11:52:13 2015
J 0
(1975 -1725);
DISPLAY 1.361702 (1975 -1725);
PAINT GREEN (1975 -1725);
DISPLAY INVISIBLE (1975 -1725);
FORCEPROP 1 LAST CUSTOM_TXT_CDS <CURRENT_DESIGN_SHEET> OF <TOTAL_DESIGN_SHEETS>
J 0
(2900 -2025);
PAINT GREEN (2900 -2025);
FORCEPROP 2 LAST CUSTOM_TXT_CDS <XR_PAGE_TITLE>
J 0
(-4490 3200);
DISPLAY 0.638298 (-4490 3200);
PAINT PINK (-4490 3200);
DISPLAY INVISIBLE (-4490 3200);
FORCEPROP 2 LAST CUSTOM_TXT_CDS <CON_LAST_MODIFIED>
J 0
(1475 -1700);
DISPLAY 1.361702 (1475 -1700);
PAINT GREEN (1475 -1700);
FORCEPROP 1 LAST SCH_TITLE SATA DOWN CONNECTOR
J 0
(-4550 -2000);
DISPLAY 1.212766 (-4550 -2000);
PAINT ORANGE (-4550 -2000);
FORCEPROP 1 LAST SCH_ADDRESS2 P.O. BOX 58119
J 0
(-575 -1975);
DISPLAY 0.617021 (-575 -1975);
PAINT GREEN (-575 -1975);
FORCEPROP 1 LAST SCH_ADDRESS1 2200 Mission College Blvd.
J 0
(-575 -1925);
DISPLAY 0.617021 (-575 -1925);
PAINT GREEN (-575 -1925);
FORCEPROP 1 LAST SCH_ADDRESS3 Santa Clara, CA 95052-8119
J 0
(-575 -2025);
DISPLAY 0.617021 (-575 -2025);
PAINT GREEN (-575 -2025);
FORCEPROP 1 LAST SCH_REV 2.420
J 0
(3150 -1900);
DISPLAY 0.978723 (3150 -1900);
PAINT YELLOW (3150 -1900);
FORCEPROP 1 LAST SCH_DEPT BESD
J 1
(-1050 -1950);
DISPLAY 1.212766 (-1050 -1950);
PAINT YELLOW (-1050 -1950);
FORCEPROP 1 LAST SCH_NUMBER H4694802
J 0
(2100 -1900);
DISPLAY 1.212766 (2100 -1900);
PAINT YELLOW (2100 -1900);
FORCEPROP 2 LAST BOM_COST ST_SATA
J 0
(-4475 3250);
PAINT MONO (-4475 3250);
DISPLAY INVISIBLE (-4475 3250);
FORCEPROP 2 LAST PAGE_BORDER TRUE
J 0
(-4490 3200);
DISPLAY 0.872340 (-4490 3200);
PAINT PINK (-4490 3200);
DISPLAY INVISIBLE (-4490 3200);
FORCEPROP 1 LAST COMMENT_BODY TRUE
J 0
(3412 -2038);
DISPLAY 0.617021 (3412 -2038);
PAINT GREEN (3412 -2038);
DISPLAY INVISIBLE (3412 -2038);
FORCEPROP 2 LAST CDS_LIB mstr_symbols
J 0
(3400 -2050);
DISPLAY 1.361702 (3400 -2050);
PAINT ORANGE (3400 -2050);
DISPLAY INVISIBLE (3400 -2050);
FORCEPROP 2 LAST CDS_XR_PAGE_TITLE CR-172 : @BASEBOARD_FAB2_LIB.BASEBOARD_FAB2(SCH_1):PAGE172
J 0
(-4490 3200);
DISPLAY 0.638298 (-4490 3200);
PAINT PINK (-4490 3200);
DISPLAY INVISIBLE (-4490 3200);
WIRE 16 -1 (-1650 300)(-1700 300);
WIRE 16 -1 (-1650 300)(-1650 200);
WIRE 16 -1 (-1650 200)(-1650 50);
WIRE 16 -1 (-1650 200)(-1700 200);
WIRE 16 -1 (-1650 50)(-1700 50);
WIRE 16 -1 (-1650 50)(-1650 -100);
WIRE 16 -1 (-1650 -100)(-1650 -200);
WIRE 16 -1 (-1650 -100)(-1700 -100);
WIRE 16 -1 (-1650 -200)(-1700 -200);
WIRE 16 -1 (-1650 -200)(-1650 -375);
WIRE 16 -1 (-200 1900)(-300 1900);
WIRE 16 -1 (-300 1900)(-300 1850);
WIRE 16 -1 (-200 1850)(-300 1850);
WIRE 16 -1 (-300 1850)(-300 1600);
WIRE 16 -1 (-1125 1350)(-1125 1475);
WIRE 16 -1 (-1975 1800)(-2100 1800);
WIRE 16 -1 (-2100 2025)(-2100 1800);
WIRE 16 -1 (-700 1350)(-700 1475);
WIRE 16 -1 (-1425 2225)(-1425 1950);
WIRE 16 -1 (-1425 1950)(-1325 1950);
WIRE 16 -1 (-1675 -825)(-1725 -825);
WIRE 16 -1 (-1675 -825)(-1675 -925);
WIRE 16 -1 (-1675 -925)(-1725 -925);
WIRE 16 -1 (-1675 -925)(-1675 -1075);
WIRE 16 -1 (-1675 -1075)(-1725 -1075);
WIRE 16 -1 (-1675 -1075)(-1675 -1225);
WIRE 16 -1 (-1675 -1225)(-1725 -1225);
WIRE 16 -1 (-1675 -1225)(-1675 -1325);
WIRE 16 -1 (-1675 -1325)(-1675 -1500);
WIRE 16 -1 (-1675 -1325)(-1725 -1325);
WIRE 16 -1 (-175 925)(-325 925);
WIRE 16 -1 (-325 925)(-325 875);
WIRE 16 -1 (-325 875)(-175 875);
WIRE 16 -1 (-325 875)(-325 625);
WIRE 16 -1 (-1025 1950)(-700 1950);
FORCEPROP 2 LAST SIG_NAME P5V_HDD_SATA
J 0
(-935 1960);
DISPLAY 0.617021 (-935 1960);
PAINT ORANGE (-935 1960);
FORCEPROP 2 LASTPROP $XRERR UNIQUE?
J 0
(-1175 1960);
DISPLAY 0.638298 (-1175 1960);
PAINT MONO (-1175 1960);
DISPLAY INVISIBLE (-1175 1960);
WIRE 16 -1 (-375 1950)(-700 1950);
FORCEPROP 0 LAST VOLTAGE 5
J 0
(-525 2000);
DISPLAY 1.021277 (-525 2000);
PAINT SKYBLUE (-525 2000);
DISPLAY INVISIBLE (-525 2000);
WIRE 16 -1 (-700 1675)(-700 1950);
WIRE 16 -1 (-375 1950)(-200 1950);
WIRE 16 -1 (-375 1950)(-375 975);
WIRE 16 -1 (-375 975)(-175 975);
WIRE 16 -1 (-1125 1675)(-1125 1800);
WIRE 16 -1 (-425 1800)(-1125 1800);
WIRE 16 -1 (-1675 1800)(-1125 1800);
FORCEPROP 0 LAST VOLTAGE 12
J 0
(-1500 1875);
DISPLAY 1.021277 (-1500 1875);
PAINT SKYBLUE (-1500 1875);
DISPLAY INVISIBLE (-1500 1875);
FORCEPROP 2 LAST SIG_NAME P12V_HDD_SATA
J 0
(-1510 1810);
DISPLAY 0.617021 (-1510 1810);
PAINT ORANGE (-1510 1810);
FORCEPROP 2 LASTPROP $XRERR UNIQUE?
J 0
(-1750 1810);
DISPLAY 0.638298 (-1750 1810);
PAINT MONO (-1750 1810);
DISPLAY INVISIBLE (-1750 1810);
WIRE 16 -1 (-200 1800)(-425 1800);
WIRE 16 -1 (-425 1800)(-425 825);
WIRE 16 -1 (-425 825)(-175 825);
WIRE 16 -1 (200 100)(1425 100);
FORCEPROP 2 LAST SIG_NAME SATA6G_S1_TX_DN
J 0
(990 110);
DISPLAY 0.617021 (990 110);
PAINT ORANGE (990 110);
WIRE 16 -1 (675 0)(1450 0);
FORCEPROP 2 LAST SIG_NAME SATA6G_S1_RX_DP
J 0
(990 10);
DISPLAY 0.617021 (990 10);
PAINT ORANGE (990 10);
WIRE 16 -1 (-1700 100)(-1050 100);
FORCEPROP 2 LAST SIG_NAME SATA6G_S1_TX_C_DN
J 0
(-1585 110);
DISPLAY 0.617021 (-1585 110);
PAINT ORANGE (-1585 110);
FORCEPROP 2 LASTPROP $XRERR UNIQUE?
J 0
(-1825 110);
DISPLAY 0.638298 (-1825 110);
PAINT MONO (-1825 110);
DISPLAY INVISIBLE (-1825 110);
WIRE 16 -1 (-1050 100)(0 100);
WIRE 16 -1 (-1050 100)(-1050 -1025);
WIRE 16 -1 (-1725 -1025)(-1050 -1025);
WIRE 16 -1 (-1700 0)(-875 0);
FORCEPROP 2 LAST SIG_NAME SATA6G_S1_RX_C_DP
J 0
(-1585 10);
DISPLAY 0.617021 (-1585 10);
PAINT ORANGE (-1585 10);
FORCEPROP 2 LASTPROP $XRERR UNIQUE?
J 0
(-1825 10);
DISPLAY 0.638298 (-1825 10);
PAINT MONO (-1825 10);
DISPLAY INVISIBLE (-1825 10);
WIRE 16 -1 (-875 0)(475 0);
WIRE 16 -1 (-875 0)(-875 -1125);
WIRE 16 -1 (-1725 -1125)(-875 -1125);
WIRE 16 -1 (-200 -50)(1450 -50);
FORCEPROP 2 LAST SIG_NAME SATA6G_S1_RX_DN
J 0
(990 -40);
DISPLAY 0.617021 (990 -40);
PAINT ORANGE (990 -40);
WIRE 16 -1 (-550 150)(1425 150);
FORCEPROP 2 LAST SIG_NAME SATA6G_S1_TX_DP
J 0
(990 160);
DISPLAY 0.617021 (990 160);
PAINT ORANGE (990 160);
WIRE 16 -1 (-1700 150)(-1100 150);
FORCEPROP 2 LAST SIG_NAME SATA6G_S1_TX_C_DP
J 0
(-1585 160);
DISPLAY 0.617021 (-1585 160);
PAINT ORANGE (-1585 160);
FORCEPROP 2 LASTPROP $XRERR UNIQUE?
J 0
(-1825 160);
DISPLAY 0.638298 (-1825 160);
PAINT MONO (-1825 160);
DISPLAY INVISIBLE (-1825 160);
WIRE 16 -1 (-1100 150)(-750 150);
WIRE 16 -1 (-1100 150)(-1100 -975);
WIRE 16 -1 (-1725 -975)(-1100 -975);
WIRE 16 -1 (-825 -50)(-400 -50);
WIRE 16 -1 (-825 -50)(-825 -1175);
WIRE 16 -1 (-1700 -50)(-825 -50);
FORCEPROP 2 LAST SIG_NAME SATA6G_S1_RX_C_DN
J 0
(-1585 -40);
DISPLAY 0.617021 (-1585 -40);
PAINT ORANGE (-1585 -40);
FORCEPROP 2 LASTPROP $XRERR UNIQUE?
J 0
(-1825 -40);
DISPLAY 0.638298 (-1825 -40);
PAINT MONO (-1825 -40);
DISPLAY INVISIBLE (-1825 -40);
WIRE 16 -1 (-1725 -1175)(-825 -1175);
DOT 1 (-1675 -1325);
DOT 1 (-1675 -1225);
DOT 1 (-1675 -1075);
DOT 1 (-1675 -925);
DOT 1 (-1650 -100);
DOT 1 (-1650 -200);
DOT 1 (-875 0);
DOT 1 (-825 -50);
DOT 1 (-1650 50);
DOT 1 (-1650 200);
DOT 1 (-1050 100);
DOT 1 (-1100 150);
DOT 1 (-1125 1800);
DOT 1 (-325 875);
DOT 1 (-700 1950);
DOT 1 (-425 1800);
DOT 1 (-375 1950);
DOT 1 (-300 1850);
FORCENOTE
ROOM=ST_SATA
(-4440 -1908) 0;
DISPLAY LEFT (-4440 -1908);
DISPLAY 0.617021 (-4440 -1908);
PAINT PURPLE (-4440 -1908);
FORCENOTE
2.6A, 16V, POLY
(-1875 1875) 0;
DISPLAY LEFT (-1875 1875);
DISPLAY 0.617021 (-1875 1875);
PAINT PURPLE (-1875 1875);
FORCENOTE
1.5A, 12V, POLY
(-1200 2050) 0;
DISPLAY LEFT (-1200 2050);
DISPLAY 0.617021 (-1200 2050);
PAINT PURPLE (-1200 2050);
QUIT
